# BASEBOARD_FAB2 (Tioga Pass) — schematic netlist excerpt (pin names and nets, part order shuffled) for the footprints in the layout excerpt that follows; sources: Cadence DE-HDL packaged netlist, KiCad conversion of Wiwynn_Tioga_Pass_MB.brd

R2T33  RES  33.2 1% CHIP  pkg 0402  page 93 : A = FM_CPU_ERR1_LVT3_K_N ; B = FM_CPU_ERR1_LVT3_N
C1D15  SC1U10V2KX-4-GP  10%  pkg SMD-BCG6  page 208 : \1\ = P5V_STBY ; \2\ = GND
C5T6  CAP_A  47UF 4V 20% X5R  pkg 0603V  page 217 : A = PVDDQ_ABC ; B = GND

(kicad_pcb
	(version 20260206)
	(generator "pcbnew")
	(generator_version "10.0")
	(general
		(thickness 1.6)
		(legacy_teardrops no)
	)
	(paper "A4")
	(title_block
		(title "Wiwynn_Tioga_Pass_MB.brd")
		(comment 1 "Tioga Pass / footprints 4070-4072 of 4770")
	)
	(layers
		(0 "F.Cu" signal "TOP")
		(4 "In1.Cu" signal "L2GND")
		(6 "In2.Cu" signal "L3")
		(8 "In3.Cu" signal "L4GND")
		(10 "In4.Cu" signal "L5")
		(12 "In5.Cu" signal "L6GND")
		(14 "In6.Cu" signal "L7VCC")
		(16 "In7.Cu" signal "L8VCC")
		(18 "In8.Cu" signal "L9GND")
		(20 "In9.Cu" signal "L10")
		(22 "In10.Cu" signal "L11GND")
		(24 "In11.Cu" signal "L12")
		(26 "In12.Cu" signal "L13GND")
		(2 "B.Cu" signal "BOTTOM")
		(9 "F.Adhes" user "F.Adhesive")
		(11 "B.Adhes" user "B.Adhesive")
		(13 "F.Paste" user "Package Geometry/Pastemask Top")
		(15 "B.Paste" user "Package Geometry/Pastemask Bottom")
		(5 "F.SilkS" user "Ref Des/Silkscreen Top")
		(7 "B.SilkS" user "Ref Des/Silkscreen Bottom")
		(1 "F.Mask" user "Board Geometry/Soldermask Top")
		(3 "B.Mask" user "Board Geometry/Soldermask Bottom")
		(17 "Dwgs.User" user "User.Drawings")
		(19 "Cmts.User" user "User.Comments")
		(21 "Eco1.User" user "User.Eco1")
		(23 "Eco2.User" user "User.Eco2")
		(25 "Edge.Cuts" user "Board Geometry/Outline")
		(27 "Margin" user)
		(31 "F.CrtYd" user "Package Geometry/Place Bound Top")
		(29 "B.CrtYd" user "Package Geometry/Place Bound Bottom")
		(35 "F.Fab" user "Ref Des/Assembly Top")
		(33 "B.Fab" user "Ref Des/Assembly Bottom")
	)
	(footprint ""
		(layer "B.Cu")
		(at 272.861532 -17.7546 90)
		(property "Reference" "C5T6"
			(at -1.848866 0.752348 90)
			(unlocked yes)
			(layer "B.SilkS")
			(effects
				(font
					(size 1.27 0.9652)
					(thickness 0.1524)
				)
				(justify mirror)
			)
		)
		(property "Value" ""
			(at 0 0 90)
			(layer "B.Fab")
			(effects
				(font
					(size 1.27 1.27)
				)
				(justify mirror)
			)
		)
		(duplicate_pad_numbers_are_jumpers no)
		(fp_rect
			(start 0.500126 1.598422)
			(end -0.500126 -0.201422)
			(stroke
				(width 0)
				(type default)
			)
			(fill no)
			(layer "B.CrtYd")
		)
		(fp_line
			(start 0.500126 -0.201422)
			(end -0.500126 -0.201422)
			(stroke
				(width 0.1)
				(type default)
			)
			(layer "B.Fab")
		)
		(fp_line
			(start -0.500126 -0.201422)
			(end -0.500126 1.598422)
			(stroke
				(width 0.1)
				(type default)
			)
			(layer "B.Fab")
		)
		(fp_line
			(start 0.500126 1.598422)
			(end 0.500126 -0.201422)
			(stroke
				(width 0.1)
				(type default)
			)
			(layer "B.Fab")
		)
		(fp_line
			(start -0.500126 1.598422)
			(end 0.500126 1.598422)
			(stroke
				(width 0.1)
				(type default)
			)
			(layer "B.Fab")
		)
		(pad "1" smd rect
			(at 0 0)
			(size 0.889 0.9906)
			(layers "B.Cu" "B.Mask" "B.Paste")
			(net "PVDDQ_ABC")
		)
		(pad "2" smd rect
			(at 0 1.397)
			(size 0.889 0.9906)
			(layers "B.Cu" "B.Mask" "B.Paste")
			(net "GND")
		)
		(zone
			(layer "B.Cu")
			(hatch none 0.5)
			(connect_pads
				(clearance 0)
			)
			(min_thickness 0.25)
			(keepout
				(tracks not_allowed)
				(vias allowed)
				(pads allowed)
				(copperpour not_allowed)
				(footprints allowed)
			)
			(placement
				(enabled no)
				(sheetname "")
			)
			(fill
				(thermal_gap 0.5)
				(thermal_bridge_width 0.5)
				(island_removal_mode 0)
			)
			(polygon
				(pts
					(xy 273.814032 -18.2499) (xy 273.306032 -18.2499) (xy 273.306032 -17.2593) (xy 273.814032 -17.2593)
				)
			)
		)
		(zone
			(layer "B.Cu")
			(hatch none 0.5)
			(connect_pads
				(clearance 0)
			)
			(min_thickness 0.25)
			(keepout
				(tracks allowed)
				(vias not_allowed)
				(pads allowed)
				(copperpour not_allowed)
				(footprints allowed)
			)
			(placement
				(enabled no)
				(sheetname "")
			)
			(fill
				(thermal_gap 0.5)
				(thermal_bridge_width 0.5)
				(island_removal_mode 0)
			)
			(polygon
				(pts
					(xy 273.814032 -18.2499) (xy 273.306032 -18.2499) (xy 273.306032 -17.2593) (xy 273.814032 -17.2593)
				)
			)
		)
	)
	(footprint ""
		(layer "B.Cu")
		(at 361.444794 -43.194986 -90)
		(property "Reference" "R2T33"
			(at 0 0 90)
			(layer "B.SilkS")
			(hide yes)
			(effects
				(font
					(size 1.27 1.27)
				)
				(justify mirror)
			)
		)
		(property "Value" ""
			(at 0 0 90)
			(layer "B.Fab")
			(effects
				(font
					(size 1.27 1.27)
				)
				(justify mirror)
			)
		)
		(duplicate_pad_numbers_are_jumpers no)
		(fp_poly
			(pts
				(xy 0.2794 -0.1016) (xy -0.2794 -0.1016) (xy -0.2794 0.9906) (xy 0.2794 0.9906)
			)
			(stroke
				(width 0)
				(type default)
			)
			(fill no)
			(layer "B.CrtYd")
		)
		(fp_line
			(start -0.2794 0.9906)
			(end -0.2794 -0.1016)
			(stroke
				(width 0.1)
				(type default)
			)
			(layer "B.Fab")
		)
		(fp_line
			(start 0.2794 0.9906)
			(end -0.2794 0.9906)
			(stroke
				(width 0.1)
				(type default)
			)
			(layer "B.Fab")
		)
		(fp_line
			(start -0.2794 -0.1016)
			(end 0.2794 -0.1016)
			(stroke
				(width 0.1)
				(type default)
			)
			(layer "B.Fab")
		)
		(fp_line
			(start 0.2794 -0.1016)
			(end 0.2794 0.9906)
			(stroke
				(width 0.1)
				(type default)
			)
			(layer "B.Fab")
		)
		(pad "1" smd rect
			(at 0 0 90)
			(size 0.508 0.508)
			(layers "B.Cu" "B.Mask" "B.Paste")
			(net "FM_CPU_ERR1_LVT3_K_N")
		)
		(pad "2" smd rect
			(at 0 0.889 90)
			(size 0.508 0.508)
			(layers "B.Cu" "B.Mask" "B.Paste")
			(net "FM_CPU_ERR1_LVT3_N")
		)
		(zone
			(layer "B.Cu")
			(hatch none 0.5)
			(connect_pads
				(clearance 0)
			)
			(min_thickness 0.25)
			(keepout
				(tracks not_allowed)
				(vias allowed)
				(pads allowed)
				(copperpour not_allowed)
				(footprints allowed)
			)
			(placement
				(enabled no)
				(sheetname "")
			)
			(fill
				(thermal_gap 0.5)
				(thermal_bridge_width 0.5)
				(island_removal_mode 0)
			)
			(polygon
				(pts
					(xy 360.809794 -42.940986) (xy 360.809794 -43.448986) (xy 361.190794 -43.448986) (xy 361.190794 -42.940986)
				)
			)
		)
		(zone
			(layer "B.Cu")
			(hatch none 0.5)
			(connect_pads
				(clearance 0)
			)
			(min_thickness 0.25)
			(keepout
				(tracks allowed)
				(vias not_allowed)
				(pads allowed)
				(copperpour not_allowed)
				(footprints allowed)
			)
			(placement
				(enabled no)
				(sheetname "")
			)
			(fill
				(thermal_gap 0.5)
				(thermal_bridge_width 0.5)
				(island_removal_mode 0)
			)
			(polygon
				(pts
					(xy 361.190794 -42.940986) (xy 361.190794 -43.448986) (xy 360.809794 -43.448986) (xy 360.809794 -42.940986)
				)
			)
		)
	)
	(footprint ""
		(layer "B.Cu")
		(at 33.5407 -69.4182 90)
		(property "Reference" "C1D15"
			(at 0 0 90)
			(layer "B.SilkS")
			(hide yes)
			(effects
				(font
					(size 1.27 1.27)
				)
				(justify mirror)
			)
		)
		(property "Value" "*"
			(at -1.1811 -2.8194 90)
			(unlocked yes)
			(layer "B.Fab")
			(hide yes)
			(effects
				(font
					(size 1.27 1.016)
					(thickness 0.1524)
				)
				(justify mirror)
			)
		)
		(property "Device Type" "SC1U10V2KX-4-GP_SMD-BCG6-SC1U1A"
			(at -1.1811 -4.3434 90)
			(unlocked yes)
			(layer "B.Fab")
			(hide yes)
			(effects
				(font
					(size 1.27 1.016)
					(thickness 0.1524)
				)
				(justify mirror)
			)
		)
		(duplicate_pad_numbers_are_jumpers no)
		(fp_rect
			(start 0.4318 0.9525)
			(end -0.4318 -0.9525)
			(stroke
				(width 0)
				(type default)
			)
			(fill no)
			(layer "B.CrtYd")
		)
		(fp_rect
			(start 0.4318 0.9525)
			(end -0.4318 -0.9525)
			(stroke
				(width 0)
				(type default)
			)
			(fill no)
			(layer "B.Fab")
		)
		(pad "1" smd custom
			(at 0 -0.4445 270)
			(size 0.1524 0.1524)
			(layers "B.Cu" "B.Mask" "B.Paste")
			(net "P5V_STBY")
			(options
				(clearance outline)
				(anchor circle)
			)
			(primitives
				(gr_poly
					(pts
						(arc
							(start 0.3048 0.2032)
							(mid 0.275042 0.275042)
							(end 0.2032 0.3048)
						)
						(arc
							(start -0.2032 0.3048)
							(mid -0.275042 0.275042)
							(end -0.3048 0.2032)
						)
						(arc
							(start -0.3048 -0.2032)
							(mid -0.275042 -0.275042)
							(end -0.2032 -0.3048)
						)
						(arc
							(start 0.2032 -0.3048)
							(mid 0.275042 -0.275042)
							(end 0.3048 -0.2032)
						)
					)
					(width 0)
					(fill yes)
				)
			)
		)
		(pad "2" smd custom
			(at 0 0.4445 270)
			(size 0.1524 0.1524)
			(layers "B.Cu" "B.Mask" "B.Paste")
			(net "GND")
			(options
				(clearance outline)
				(anchor circle)
			)
			(primitives
				(gr_poly
					(pts
						(arc
							(start 0.3048 0.2032)
							(mid 0.275042 0.275042)
							(end 0.2032 0.3048)
						)
						(arc
							(start -0.2032 0.3048)
							(mid -0.275042 0.275042)
							(end -0.3048 0.2032)
						)
						(arc
							(start -0.3048 -0.2032)
							(mid -0.275042 -0.275042)
							(end -0.2032 -0.3048)
						)
						(arc
							(start 0.2032 -0.3048)
							(mid 0.275042 -0.275042)
							(end 0.3048 -0.2032)
						)
					)
					(width 0)
					(fill yes)
				)
			)
		)
	)
)
